(kicad_pcb
	(version 20241229)
	(generator "pcbnew")
	(generator_version "9.0")
	(general
		(thickness 1.599998)
		(legacy_teardrops no)
	)
	(paper "A4")
	(title_block
		(date "2023-02-12")
		(rev "1.1.5")
		(comment 9 "footprints 303-309 of 473")
	)
	(layers
		(0 "F.Cu" signal)
		(4 "In1.Cu" power "In1.GND")
		(6 "In2.Cu" signal)
		(8 "In3.Cu" power "In3.GND")
		(10 "In4.Cu" power "In4.VCC")
		(12 "In5.Cu" signal)
		(14 "In6.Cu" power "In6.VCC")
		(2 "B.Cu" signal)
		(9 "F.Adhes" user "F.Adhesive")
		(11 "B.Adhes" user "B.Adhesive")
		(13 "F.Paste" user)
		(15 "B.Paste" user)
		(5 "F.SilkS" user "F.Silkscreen")
		(7 "B.SilkS" user "B.Silkscreen")
		(1 "F.Mask" user)
		(3 "B.Mask" user)
		(17 "Dwgs.User" user "User.Drawings")
		(19 "Cmts.User" user "User.Comments")
		(21 "Eco1.User" user "User.Eco1")
		(23 "Eco2.User" user "User.Eco2")
		(25 "Edge.Cuts" user)
		(27 "Margin" user)
		(31 "F.CrtYd" user "F.Courtyard")
		(29 "B.CrtYd" user "B.Courtyard")
		(35 "F.Fab" user)
		(33 "B.Fab" user)
	)
	(footprint "antmicro-footprints:C_0402_1005Metric"
		(layer "F.Cu")
		(at 190.3 111.635 90)
		(descr "Capacitor SMD 0402")
		(tags "capacitor SMD 0402")
		(property "Reference" "C180"
			(at 0.735 0.4 90)
			(layer "F.SilkS")
			(effects
				(font
					(size 0.7 0.7)
					(thickness 0.15)
				)
				(justify left bottom)
			)
		)
		(property "Value" "C_1u_0402"
			(at 0 1.4 90)
			(layer "F.Fab")
			(effects
				(font
					(size 0.7 0.7)
					(thickness 0.15)
				)
				(justify left bottom)
			)
		)
		(property "Description" " "
			(at 0 0 90)
			(layer "F.Fab")
			(hide yes)
			(effects
				(font
					(size 1.27 1.27)
					(thickness 0.15)
				)
			)
		)
		(property "Author" "Antmicro"
			(at 301.935 -78.665 0)
			(layer "F.Fab")
			(hide yes)
			(effects
				(font
					(size 1 1)
					(thickness 0.15)
				)
			)
		)
		(property "Dielectric" ""
			(at 301.935 -78.665 0)
			(layer "F.Fab")
			(hide yes)
			(effects
				(font
					(size 1 1)
					(thickness 0.15)
				)
			)
		)
		(property "License" "Apache-2.0"
			(at 301.935 -78.665 0)
			(layer "F.Fab")
			(hide yes)
			(effects
				(font
					(size 1 1)
					(thickness 0.15)
				)
			)
		)
		(property "MPN" "C1005X6S1A105K050BC"
			(at 301.935 -78.665 0)
			(layer "F.Fab")
			(hide yes)
			(effects
				(font
					(size 1 1)
					(thickness 0.15)
				)
			)
		)
		(property "Manufacturer" "TDK"
			(at 301.935 -78.665 0)
			(layer "F.Fab")
			(hide yes)
			(effects
				(font
					(size 1 1)
					(thickness 0.15)
				)
			)
		)
		(property "Val" "1u"
			(at 301.935 -78.665 0)
			(layer "F.Fab")
			(hide yes)
			(effects
				(font
					(size 1 1)
					(thickness 0.15)
				)
			)
		)
		(property "Voltage" ""
			(at 301.935 -78.665 0)
			(layer "F.Fab")
			(hide yes)
			(effects
				(font
					(size 1 1)
					(thickness 0.15)
				)
			)
		)
		(sheetname "Supply")
		(sheetfile "supply.kicad_sch")
		(attr smd)
		(fp_rect
			(start -0.94 -0.47)
			(end 0.94 0.47)
			(stroke
				(width 0.05)
				(type solid)
			)
			(fill no)
			(layer "F.CrtYd")
		)
		(fp_rect
			(start -0.499 -0.249)
			(end 0.499 0.249)
			(stroke
				(width 0.15)
				(type solid)
			)
			(fill no)
			(layer "F.Fab")
		)
		(pad "1" smd roundrect
			(at -0.484 0 90)
			(size 0.59 0.64)
			(layers "F.Cu" "F.Mask" "F.Paste")
			(roundrect_rratio 0.25)
			(net 589 "/Supply/1V2_REG")
			(pintype "passive")
		)
		(pad "2" smd roundrect
			(at 0.484 0 90)
			(size 0.59 0.64)
			(layers "F.Cu" "F.Mask" "F.Paste")
			(roundrect_rratio 0.25)
			(net 5 "GND")
			(pintype "passive")
		)
	)
	(footprint "antmicro-footprints:R_0805_2012Metric"
		(layer "F.Cu")
		(at 134.4 56.1 -90)
		(property "Reference" "R97"
			(at 1.7 -1.8 270)
			(layer "F.SilkS")
			(effects
				(font
					(size 0.7 0.7)
					(thickness 0.15)
				)
				(justify left bottom)
			)
		)
		(property "Value" "R_0R_0805"
			(at 0 1.8 270)
			(layer "F.Fab")
			(effects
				(font
					(size 0.7 0.7)
					(thickness 0.15)
				)
				(justify left bottom)
			)
		)
		(property "Description" "0R resistor in 0805 package with unspecified tolerance"
			(at 0 0 270)
			(layer "F.Fab")
			(hide yes)
			(effects
				(font
					(size 1.27 1.27)
					(thickness 0.15)
				)
			)
		)
		(property "Author" "Antmicro"
			(at 78.3 190.5 0)
			(layer "F.Fab")
			(hide yes)
			(effects
				(font
					(size 1 1)
					(thickness 0.15)
				)
			)
		)
		(property "Current" "2.5A"
			(at 78.3 190.5 0)
			(layer "F.Fab")
			(hide yes)
			(effects
				(font
					(size 1 1)
					(thickness 0.15)
				)
			)
		)
		(property "License" "Apache-2.0"
			(at 78.3 190.5 0)
			(layer "F.Fab")
			(hide yes)
			(effects
				(font
					(size 1 1)
					(thickness 0.15)
				)
			)
		)
		(property "MPN" "CRCW08050000Z0EA"
			(at 78.3 190.5 0)
			(layer "F.Fab")
			(hide yes)
			(effects
				(font
					(size 1 1)
					(thickness 0.15)
				)
			)
		)
		(property "Manufacturer" "Vishay"
			(at 78.3 190.5 0)
			(layer "F.Fab")
			(hide yes)
			(effects
				(font
					(size 1 1)
					(thickness 0.15)
				)
			)
		)
		(property "Tolerance" ""
			(at 78.3 190.5 0)
			(layer "F.Fab")
			(hide yes)
			(effects
				(font
					(size 1 1)
					(thickness 0.15)
				)
			)
		)
		(property "Val" "0R"
			(at 78.3 190.5 0)
			(layer "F.Fab")
			(hide yes)
			(effects
				(font
					(size 1 1)
					(thickness 0.15)
				)
			)
		)
		(sheetname "Supply")
		(sheetfile "supply.kicad_sch")
		(attr exclude_from_pos_files exclude_from_bom dnp)
		(fp_line
			(start -0.32 0.699)
			(end 0.28 0.699)
			(stroke
				(width 0.15)
				(type solid)
			)
			(layer "F.SilkS")
		)
		(fp_line
			(start -0.3 -0.701)
			(end 0.298 -0.701)
			(stroke
				(width 0.15)
				(type solid)
			)
			(layer "F.SilkS")
		)
		(fp_rect
			(start -1.75 -0.85)
			(end 1.75 0.85)
			(stroke
				(width 0.05)
				(type solid)
			)
			(fill no)
			(layer "F.CrtYd")
		)
		(fp_line
			(start -0.951 0.68)
			(end 0.949 0.68)
			(stroke
				(width 0.15)
				(type solid)
			)
			(layer "F.Fab")
		)
		(fp_line
			(start -0.951 -0.677)
			(end -0.951 0.675)
			(stroke
				(width 0.15)
				(type solid)
			)
			(layer "F.Fab")
		)
		(fp_line
			(start 0.949 -0.677)
			(end 0.949 0.675)
			(stroke
				(width 0.15)
				(type solid)
			)
			(layer "F.Fab")
		)
		(fp_line
			(start -0.951 -0.682)
			(end 0.949 -0.682)
			(stroke
				(width 0.15)
				(type solid)
			)
			(layer "F.Fab")
		)
		(pad "1" smd roundrect
			(at -1.1 -0.001 270)
			(size 1 1.4)
			(layers "F.Cu" "F.Mask" "F.Paste")
			(roundrect_rratio 0.15)
			(net 550 "VDD1V1")
			(pintype "passive")
		)
		(pad "2" smd roundrect
			(at 1.1 -0.001 270)
			(size 1 1.4)
			(layers "F.Cu" "F.Mask" "F.Paste")
			(roundrect_rratio 0.15)
			(net 461 "1V1_SYS")
			(pintype "passive")
		)
	)
	(footprint "antmicro-footprints:C_0603_1608Metric"
		(layer "F.Cu")
		(at 139.1 63.5 90)
		(descr "Capacitor SMD 0603")
		(tags "capacitor 0603")
		(property "Reference" "C140"
			(at -3.9 0.9 90)
			(layer "F.SilkS")
			(effects
				(font
					(size 0.7 0.7)
					(thickness 0.15)
				)
				(justify left bottom)
			)
		)
		(property "Value" "C_47u_0603"
			(at 0 1.6 90)
			(layer "F.Fab")
			(effects
				(font
					(size 0.7 0.7)
					(thickness 0.15)
				)
				(justify left bottom)
			)
		)
		(property "Description" " "
			(at 0 0 90)
			(layer "F.Fab")
			(hide yes)
			(effects
				(font
					(size 1.27 1.27)
					(thickness 0.15)
				)
			)
		)
		(property "Author" "Antmicro"
			(at 202.6 -75.6 0)
			(layer "F.Fab")
			(hide yes)
			(effects
				(font
					(size 1 1)
					(thickness 0.15)
				)
			)
		)
		(property "Dielectric" ""
			(at 202.6 -75.6 0)
			(layer "F.Fab")
			(hide yes)
			(effects
				(font
					(size 1 1)
					(thickness 0.15)
				)
			)
		)
		(property "License" "Apache-2.0"
			(at 202.6 -75.6 0)
			(layer "F.Fab")
			(hide yes)
			(effects
				(font
					(size 1 1)
					(thickness 0.15)
				)
			)
		)
		(property "MPN" "GRM188R60J476ME15D"
			(at 202.6 -75.6 0)
			(layer "F.Fab")
			(hide yes)
			(effects
				(font
					(size 1 1)
					(thickness 0.15)
				)
			)
		)
		(property "Manufacturer" "Murata"
			(at 202.6 -75.6 0)
			(layer "F.Fab")
			(hide yes)
			(effects
				(font
					(size 1 1)
					(thickness 0.15)
				)
			)
		)
		(property "Val" "47u"
			(at 202.6 -75.6 0)
			(layer "F.Fab")
			(hide yes)
			(effects
				(font
					(size 1 1)
					(thickness 0.15)
				)
			)
		)
		(property "Voltage" ""
			(at 202.6 -75.6 0)
			(layer "F.Fab")
			(hide yes)
			(effects
				(font
					(size 1 1)
					(thickness 0.15)
				)
			)
		)
		(sheetname "Supply")
		(sheetfile "supply.kicad_sch")
		(attr smd)
		(fp_line
			(start -0.3 -0.3)
			(end 0.3 -0.3)
			(stroke
				(width 0.15)
				(type solid)
			)
			(layer "F.SilkS")
		)
		(fp_line
			(start -0.3 0.3)
			(end 0.3 0.3)
			(stroke
				(width 0.15)
				(type solid)
			)
			(layer "F.SilkS")
		)
		(fp_rect
			(start -1.24 -0.7)
			(end 1.24 0.7)
			(stroke
				(width 0.05)
				(type solid)
			)
			(fill no)
			(layer "F.CrtYd")
		)
		(fp_rect
			(start -0.8 -0.4)
			(end 0.8 0.4)
			(stroke
				(width 0.15)
				(type solid)
			)
			(fill no)
			(layer "F.Fab")
		)
		(pad "1" smd roundrect
			(at -0.7 0 90)
			(size 0.6 0.8)
			(layers "F.Cu" "F.Mask" "F.Paste")
			(roundrect_rratio 0.2)
			(net 633 "/Supply/0V6_REG")
			(pintype "passive")
		)
		(pad "2" smd roundrect
			(at 0.7 0 90)
			(size 0.6 0.8)
			(layers "F.Cu" "F.Mask" "F.Paste")
			(roundrect_rratio 0.2)
			(net 5 "GND")
			(pintype "passive")
		)
	)
	(footprint "antmicro-footprints:C_0603_1608Metric"
		(layer "F.Cu")
		(at 179.6 57.1 90)
		(descr "Capacitor SMD 0603")
		(tags "capacitor 0603")
		(property "Reference" "C138"
			(at -1.5 1.3 90)
			(layer "F.SilkS")
			(effects
				(font
					(size 0.7 0.7)
					(thickness 0.15)
				)
				(justify left bottom)
			)
		)
		(property "Value" "C_10n_0603"
			(at 0 1.6 90)
			(layer "F.Fab")
			(effects
				(font
					(size 0.7 0.7)
					(thickness 0.15)
				)
				(justify left bottom)
			)
		)
		(property "Description" " "
			(at 0 0 90)
			(layer "F.Fab")
			(hide yes)
			(effects
				(font
					(size 1.27 1.27)
					(thickness 0.15)
				)
			)
		)
		(property "Author" "Antmicro"
			(at 236.7 -122.5 0)
			(layer "F.Fab")
			(hide yes)
			(effects
				(font
					(size 1 1)
					(thickness 0.15)
				)
			)
		)
		(property "Dielectric" ""
			(at 236.7 -122.5 0)
			(layer "F.Fab")
			(hide yes)
			(effects
				(font
					(size 1 1)
					(thickness 0.15)
				)
			)
		)
		(property "License" "Apache-2.0"
			(at 236.7 -122.5 0)
			(layer "F.Fab")
			(hide yes)
			(effects
				(font
					(size 1 1)
					(thickness 0.15)
				)
			)
		)
		(property "MPN" "06031C103JAT2A"
			(at 236.7 -122.5 0)
			(layer "F.Fab")
			(hide yes)
			(effects
				(font
					(size 1 1)
					(thickness 0.15)
				)
			)
		)
		(property "Manufacturer" "AVX"
			(at 236.7 -122.5 0)
			(layer "F.Fab")
			(hide yes)
			(effects
				(font
					(size 1 1)
					(thickness 0.15)
				)
			)
		)
		(property "Val" "10n"
			(at 236.7 -122.5 0)
			(layer "F.Fab")
			(hide yes)
			(effects
				(font
					(size 1 1)
					(thickness 0.15)
				)
			)
		)
		(property "Voltage" ""
			(at 236.7 -122.5 0)
			(layer "F.Fab")
			(hide yes)
			(effects
				(font
					(size 1 1)
					(thickness 0.15)
				)
			)
		)
		(sheetname "Supply")
		(sheetfile "supply.kicad_sch")
		(attr smd)
		(fp_line
			(start -0.3 -0.3)
			(end 0.3 -0.3)
			(stroke
				(width 0.15)
				(type solid)
			)
			(layer "F.SilkS")
		)
		(fp_line
			(start -0.3 0.3)
			(end 0.3 0.3)
			(stroke
				(width 0.15)
				(type solid)
			)
			(layer "F.SilkS")
		)
		(fp_rect
			(start -1.24 -0.7)
			(end 1.24 0.7)
			(stroke
				(width 0.05)
				(type solid)
			)
			(fill no)
			(layer "F.CrtYd")
		)
		(fp_rect
			(start -0.8 -0.4)
			(end 0.8 0.4)
			(stroke
				(width 0.15)
				(type solid)
			)
			(fill no)
			(layer "F.Fab")
		)
		(pad "1" smd roundrect
			(at -0.7 0 90)
			(size 0.6 0.8)
			(layers "F.Cu" "F.Mask" "F.Paste")
			(roundrect_rratio 0.2)
			(net 66 "VDDQ")
			(pintype "passive")
		)
		(pad "2" smd roundrect
			(at 0.7 0 90)
			(size 0.6 0.8)
			(layers "F.Cu" "F.Mask" "F.Paste")
			(roundrect_rratio 0.2)
			(net 5 "GND")
			(pintype "passive")
		)
	)
	(footprint "antmicro-footprints:C_0805_2012Metric"
		(layer "F.Cu")
		(at 110.8492 112.05 90)
		(descr "Capacitor SMD 0805")
		(tags "capacitor SMD 0805")
		(property "Reference" "C127"
			(at 1.65 0.3508 90)
			(layer "F.SilkS")
			(effects
				(font
					(size 0.7 0.7)
					(thickness 0.15)
				)
				(justify left bottom)
			)
		)
		(property "Value" "C_22u_0805_16V"
			(at 0 1.947 90)
			(layer "F.Fab")
			(effects
				(font
					(size 0.7 0.7)
					(thickness 0.15)
				)
				(justify left bottom)
			)
		)
		(property "Description" " "
			(at 0 0 90)
			(layer "F.Fab")
			(hide yes)
			(effects
				(font
					(size 1.27 1.27)
					(thickness 0.15)
				)
			)
		)
		(property "Author" "Antmicro"
			(at 222.8992 1.2008 0)
			(layer "F.Fab")
			(hide yes)
			(effects
				(font
					(size 1 1)
					(thickness 0.15)
				)
			)
		)
		(property "Dielectric" ""
			(at 222.8992 1.2008 0)
			(layer "F.Fab")
			(hide yes)
			(effects
				(font
					(size 1 1)
					(thickness 0.15)
				)
			)
		)
		(property "License" "Apache-2.0"
			(at 222.8992 1.2008 0)
			(layer "F.Fab")
			(hide yes)
			(effects
				(font
					(size 1 1)
					(thickness 0.15)
				)
			)
		)
		(property "MPN" "GRT21BR61C226ME13L"
			(at 222.8992 1.2008 0)
			(layer "F.Fab")
			(hide yes)
			(effects
				(font
					(size 1 1)
					(thickness 0.15)
				)
			)
		)
		(property "Manufacturer" "Murata"
			(at 222.8992 1.2008 0)
			(layer "F.Fab")
			(hide yes)
			(effects
				(font
					(size 1 1)
					(thickness 0.15)
				)
			)
		)
		(property "Val" "22u/16V"
			(at 222.8992 1.2008 0)
			(layer "F.Fab")
			(hide yes)
			(effects
				(font
					(size 1 1)
					(thickness 0.15)
				)
			)
		)
		(property "Voltage" ""
			(at 222.8992 1.2008 0)
			(layer "F.Fab")
			(hide yes)
			(effects
				(font
					(size 1 1)
					(thickness 0.15)
				)
			)
		)
		(sheetname "Supply")
		(sheetfile "supply.kicad_sch")
		(attr smd)
		(fp_line
			(start -0.3 -0.8)
			(end 0.3 -0.8)
			(stroke
				(width 0.15)
				(type solid)
			)
			(layer "F.SilkS")
		)
		(fp_line
			(start -0.3 0.8)
			(end 0.3 0.8)
			(stroke
				(width 0.15)
				(type solid)
			)
			(layer "F.SilkS")
		)
		(fp_rect
			(start -1.9 -0.93)
			(end 1.9 0.93)
			(stroke
				(width 0.05)
				(type solid)
			)
			(fill no)
			(layer "F.CrtYd")
		)
		(fp_rect
			(start -0.95 -0.675)
			(end 0.95 0.675)
			(stroke
				(width 0.15)
				(type solid)
			)
			(fill no)
			(layer "F.Fab")
		)
		(pad "1" smd rect
			(at -1.05 0 90)
			(size 1.2 1.2)
			(layers "F.Cu" "F.Mask" "F.Paste")
			(net 224 "VIN")
			(pintype "passive")
		)
		(pad "2" smd rect
			(at 1.05 0 90)
			(size 1.2 1.2)
			(layers "F.Cu" "F.Mask" "F.Paste")
			(net 5 "GND")
			(pintype "passive")
		)
	)
	(footprint "antmicro-footprints:R_0402_1005Metric"
		(layer "F.Cu")
		(at 129.95 90.074 180)
		(descr "Resistor SMD 0402")
		(tags "resistor SMD 0402")
		(property "Reference" "R122"
			(at 1.285328 2.474 180)
			(layer "F.SilkS")
			(effects
				(font
					(size 0.7 0.7)
					(thickness 0.15)
				)
				(justify left bottom)
			)
		)
		(property "Value" "R_100k_0402"
			(at 0 1.4 180)
			(layer "F.Fab")
			(effects
				(font
					(size 0.7 0.7)
					(thickness 0.15)
				)
				(justify left bottom)
			)
		)
		(property "Description" "100k resistor in 0402 package with 1% tolerance"
			(at 0 0 180)
			(layer "F.Fab")
			(hide yes)
			(effects
				(font
					(size 1.27 1.27)
					(thickness 0.15)
				)
			)
		)
		(property "Author" "Antmicro"
			(at 259.9 180.148 0)
			(layer "F.Fab")
			(hide yes)
			(effects
				(font
					(size 1 1)
					(thickness 0.15)
				)
			)
		)
		(property "License" "Apache-2.0"
			(at 259.9 180.148 0)
			(layer "F.Fab")
			(hide yes)
			(effects
				(font
					(size 1 1)
					(thickness 0.15)
				)
			)
		)
		(property "MPN" "CR0402-FX-1003GLF"
			(at 259.9 180.148 0)
			(layer "F.Fab")
			(hide yes)
			(effects
				(font
					(size 1 1)
					(thickness 0.15)
				)
			)
		)
		(property "Manufacturer" "Bourns"
			(at 259.9 180.148 0)
			(layer "F.Fab")
			(hide yes)
			(effects
				(font
					(size 1 1)
					(thickness 0.15)
				)
			)
		)
		(property "Tolerance" "1%"
			(at 259.9 180.148 0)
			(layer "F.Fab")
			(hide yes)
			(effects
				(font
					(size 1 1)
					(thickness 0.15)
				)
			)
		)
		(property "Val" "100k"
			(at 259.9 180.148 0)
			(layer "F.Fab")
			(hide yes)
			(effects
				(font
					(size 1 1)
					(thickness 0.15)
				)
			)
		)
		(sheetname "Supply")
		(sheetfile "supply.kicad_sch")
		(attr smd)
		(fp_rect
			(start -0.93 -0.47)
			(end 0.93 0.47)
			(stroke
				(width 0.05)
				(type solid)
			)
			(fill no)
			(layer "F.CrtYd")
		)
		(fp_rect
			(start -0.5 -0.25)
			(end 0.5 0.25)
			(stroke
				(width 0.15)
				(type solid)
			)
			(fill no)
			(layer "F.Fab")
		)
		(pad "1" smd roundrect
			(at -0.485 0 180)
			(size 0.59 0.64)
			(layers "F.Cu" "F.Mask" "F.Paste")
			(roundrect_rratio 0.25)
			(net 605 "/Supply/1V8_PG")
			(pintype "passive")
		)
		(pad "2" smd roundrect
			(at 0.485 0 180)
			(size 0.59 0.64)
			(layers "F.Cu" "F.Mask" "F.Paste")
			(roundrect_rratio 0.25)
			(net 590 "/Supply/1V1_EN")
			(pintype "passive")
		)
	)
	(footprint "antmicro-footprints:R_0402_1005Metric"
		(layer "F.Cu")
		(at 140.1825 84.699)
		(descr "Resistor SMD 0402")
		(tags "resistor SMD 0402")
		(property "Reference" "R113"
			(at -3.6825 -0.699 0)
			(layer "F.SilkS")
			(effects
				(font
					(size 0.7 0.7)
					(thickness 0.15)
				)
				(justify left bottom)
			)
		)
		(property "Value" "R_330R_0402"
			(at 0 1.4 0)
			(layer "F.Fab")
			(effects
				(font
					(size 0.7 0.7)
					(thickness 0.15)
				)
				(justify left bottom)
			)
		)
		(property "Description" "330R resistor in 0402 package with 1% tolerance"
			(at 0 0 0)
			(layer "F.Fab")
			(hide yes)
			(effects
				(font
					(size 1.27 1.27)
					(thickness 0.15)
				)
			)
		)
		(property "Author" "Antmicro"
			(at 0 0 0)
			(layer "F.Fab")
			(hide yes)
			(effects
				(font
					(size 1 1)
					(thickness 0.15)
				)
			)
		)
		(property "License" "Apache-2.0"
			(at 0 0 0)
			(layer "F.Fab")
			(hide yes)
			(effects
				(font
					(size 1 1)
					(thickness 0.15)
				)
			)
		)
		(property "MPN" "CR0402-FX-3300GLF"
			(at 0 0 0)
			(layer "F.Fab")
			(hide yes)
			(effects
				(font
					(size 1 1)
					(thickness 0.15)
				)
			)
		)
		(property "Manufacturer" "Bourns"
			(at 0 0 0)
			(layer "F.Fab")
			(hide yes)
			(effects
				(font
					(size 1 1)
					(thickness 0.15)
				)
			)
		)
		(property "Tolerance" "1%"
			(at 0 0 0)
			(layer "F.Fab")
			(hide yes)
			(effects
				(font
					(size 1 1)
					(thickness 0.15)
				)
			)
		)
		(property "Val" "330R"
			(at 0 0 0)
			(layer "F.Fab")
			(hide yes)
			(effects
				(font
					(size 1 1)
					(thickness 0.15)
				)
			)
		)
		(sheetname "Supply")
		(sheetfile "supply.kicad_sch")
		(attr smd)
		(fp_rect
			(start -0.93 -0.47)
			(end 0.93 0.47)
			(stroke
				(width 0.05)
				(type solid)
			)
			(fill no)
			(layer "F.CrtYd")
		)
		(fp_rect
			(start -0.5 -0.25)
			(end 0.5 0.25)
			(stroke
				(width 0.15)
				(type solid)
			)
			(fill no)
			(layer "F.Fab")
		)
		(pad "1" smd roundrect
			(at -0.485 0)
			(size 0.59 0.64)
			(layers "F.Cu" "F.Mask" "F.Paste")
			(roundrect_rratio 0.25)
			(net 557 "Net-(PWR5-Pad2)")
			(pintype "passive")
		)
		(pad "2" smd roundrect
			(at 0.485 0)
			(size 0.59 0.64)
			(layers "F.Cu" "F.Mask" "F.Paste")
			(roundrect_rratio 0.25)
			(net 237 "Net-(Q11-D)")
			(pintype "passive")
		)
	)
)
